FILE_TYPE = CONNECTIVITY;
{Allegro Design Entry HDL 17.2-2016 S081 (4005846) 1/11/2022}
"PAGE_NUMBER" = 166;
0"NC";
1"P5E_CPU0_PE4_TX_DP<7:0>";
2"P5E_CPU0_PE4_TX_DN<7:0>";
3"P5E_CPU0_PE4_TX_DN<15:8>";
4"P5E_CPU0_PE4_TX_DP<15:8>";
5"P5E_CPU0_PE4_TX_C_DN<15:8>";
6"P5E_CPU0_PE4_TX_C_DP<15:8>";
7"P5E_CPU0_PE4_TX_C_DN<7:0>";
8"P5E_CPU0_PE4_TX_C_DP<7:0>";
9"P5E_CPU1_PE1_TX_DP<7:0>";
10"P5E_CPU1_PE1_TX_DN<7:0>";
11"P5E_CPU1_PE1_TX_DP<15:8>";
12"P5E_CPU1_PE1_TX_DN<15:8>";
13"P5E_CPU1_PE1_TX_C_DN<7:0>";
14"P5E_CPU1_PE1_TX_C_DP<7:0>";
15"P5E_CPU1_PE1_TX_C_DN<15:8>";
16"P5E_CPU1_PE1_TX_C_DP<15:8>";
17"P5E_CPU0_PE4_TX_C_DP<5>";
18"P5E_CPU0_PE4_TX_DN<6>";
19"P5E_CPU1_PE1_TX_C_DP<15>";
20"P5E_CPU1_PE1_TX_C_DP<14>";
21"P5E_CPU1_PE1_TX_C_DP<13>";
22"P5E_CPU1_PE1_TX_C_DN<12>";
23"P5E_CPU1_PE1_TX_C_DN<11>";
24"P5E_CPU1_PE1_TX_C_DP<11>";
25"P5E_CPU1_PE1_TX_C_DP<10>";
26"P5E_CPU1_PE1_TX_C_DP<9>";
27"P5E_CPU1_PE1_TX_C_DP<8>";
28"P5E_CPU1_PE1_TX_C_DP<5>";
29"P5E_CPU1_PE1_TX_C_DP<0>";
30"P5E_CPU1_PE1_TX_C_DP<1>";
31"P5E_CPU1_PE1_TX_C_DP<2>";
32"P5E_CPU1_PE1_TX_C_DP<3>";
33"P5E_CPU1_PE1_TX_DP<7>";
34"P5E_CPU1_PE1_TX_DN<7>";
35"P5E_CPU1_PE1_TX_C_DN<5>";
36"P5E_CPU1_PE1_TX_C_DP<4>";
37"P5E_CPU1_PE1_TX_C_DN<15>";
38"P5E_CPU1_PE1_TX_C_DN<14>";
39"P5E_CPU1_PE1_TX_C_DN<13>";
40"P5E_CPU1_PE1_TX_C_DP<12>";
41"P5E_CPU1_PE1_TX_C_DN<10>";
42"P5E_CPU1_PE1_TX_C_DN<9>";
43"P5E_CPU1_PE1_TX_C_DN<8>";
44"P5E_CPU1_PE1_TX_C_DN<7>";
45"P5E_CPU1_PE1_TX_C_DP<7>";
46"P5E_CPU1_PE1_TX_C_DP<6>";
47"P5E_CPU1_PE1_TX_C_DN<6>";
48"P5E_CPU1_PE1_TX_C_DN<4>";
49"P5E_CPU1_PE1_TX_C_DN<3>";
50"P5E_CPU1_PE1_TX_C_DN<2>";
51"P5E_CPU1_PE1_TX_C_DN<1>";
52"P5E_CPU1_PE1_TX_C_DN<0>";
53"P5E_CPU1_PE1_TX_DN<15>";
54"P5E_CPU1_PE1_TX_DN<14>";
55"P5E_CPU1_PE1_TX_DN<13>";
56"P5E_CPU1_PE1_TX_DP<13>";
57"P5E_CPU1_PE1_TX_DP<15>";
58"P5E_CPU1_PE1_TX_DP<14>";
59"P5E_CPU1_PE1_TX_DN<12>";
60"P5E_CPU1_PE1_TX_DN<10>";
61"P5E_CPU1_PE1_TX_DN<11>";
62"P5E_CPU1_PE1_TX_DP<12>";
63"P5E_CPU1_PE1_TX_DP<11>";
64"P5E_CPU1_PE1_TX_DP<8>";
65"P5E_CPU1_PE1_TX_DN<8>";
66"P5E_CPU1_PE1_TX_DP<9>";
67"P5E_CPU1_PE1_TX_DN<9>";
68"P5E_CPU1_PE1_TX_DP<10>";
69"P5E_CPU1_PE1_TX_DN<6>";
70"P5E_CPU1_PE1_TX_DN<5>";
71"P5E_CPU1_PE1_TX_DP<6>";
72"P5E_CPU1_PE1_TX_DP<5>";
73"P5E_CPU1_PE1_TX_DN<4>";
74"P5E_CPU1_PE1_TX_DN<3>";
75"P5E_CPU1_PE1_TX_DN<2>";
76"P5E_CPU1_PE1_TX_DN<1>";
77"P5E_CPU1_PE1_TX_DN<0>";
78"P5E_CPU1_PE1_TX_DP<3>";
79"P5E_CPU1_PE1_TX_DP<4>";
80"P5E_CPU1_PE1_TX_DP<2>";
81"P5E_CPU1_PE1_TX_DP<1>";
82"P5E_CPU1_PE1_TX_DP<0>";
83"P5E_CPU0_PE4_TX_DP<13>";
84"P5E_CPU0_PE4_TX_C_DP<11>";
85"P5E_CPU0_PE4_TX_DP<10>";
86"P5E_CPU0_PE4_TX_C_DP<9>";
87"P5E_CPU0_PE4_TX_DP<7>";
88"P5E_CPU0_PE4_TX_DN<4>";
89"P5E_CPU0_PE4_TX_DP<4>";
90"P5E_CPU0_PE4_TX_DP<3>";
91"P5E_CPU0_PE4_TX_DN<2>";
92"P5E_CPU0_PE4_TX_DN<1>";
93"P5E_CPU0_PE4_TX_DP<1>";
94"P5E_CPU0_PE4_TX_DP<2>";
95"P5E_CPU0_PE4_TX_C_DP<6>";
96"P5E_CPU0_PE4_TX_C_DN<6>";
97"P5E_CPU0_PE4_TX_C_DP<7>";
98"P5E_CPU0_PE4_TX_C_DN<7>";
99"P5E_CPU0_PE4_TX_C_DP<8>";
100"P5E_CPU0_PE4_TX_C_DN<8>";
101"P5E_CPU0_PE4_TX_C_DP<15>";
102"P5E_CPU0_PE4_TX_C_DN<15>";
103"P5E_CPU0_PE4_TX_C_DP<0>";
104"P5E_CPU0_PE4_TX_C_DN<0>";
105"P5E_CPU0_PE4_TX_C_DP<1>";
106"P5E_CPU0_PE4_TX_C_DN<1>";
107"P5E_CPU0_PE4_TX_C_DP<2>";
108"P5E_CPU0_PE4_TX_C_DN<2>";
109"P5E_CPU0_PE4_TX_C_DP<3>";
110"P5E_CPU0_PE4_TX_C_DN<3>";
111"P5E_CPU0_PE4_TX_C_DP<4>";
112"P5E_CPU0_PE4_TX_C_DN<4>";
113"P5E_CPU0_PE4_TX_C_DN<5>";
114"P5E_CPU0_PE4_TX_C_DP<10>";
115"P5E_CPU0_PE4_TX_C_DN<10>";
116"P5E_CPU0_PE4_TX_C_DN<11>";
117"P5E_CPU0_PE4_TX_C_DP<12>";
118"P5E_CPU0_PE4_TX_C_DN<12>";
119"P5E_CPU0_PE4_TX_C_DP<13>";
120"P5E_CPU0_PE4_TX_C_DN<13>";
121"P5E_CPU0_PE4_TX_C_DN<9>";
122"P5E_CPU0_PE4_TX_C_DP<14>";
123"P5E_CPU0_PE4_TX_C_DN<14>";
124"P5E_CPU0_PE4_TX_DN<11>";
125"P5E_CPU0_PE4_TX_DP<14>";
126"P5E_CPU0_PE4_TX_DP<15>";
127"P5E_CPU0_PE4_TX_DP<8>";
128"P5E_CPU0_PE4_TX_DP<11>";
129"P5E_CPU0_PE4_TX_DP<9>";
130"P5E_CPU0_PE4_TX_DP<12>";
131"P5E_CPU0_PE4_TX_DN<8>";
132"P5E_CPU0_PE4_TX_DN<12>";
133"P5E_CPU0_PE4_TX_DN<9>";
134"P5E_CPU0_PE4_TX_DN<10>";
135"P5E_CPU0_PE4_TX_DN<14>";
136"P5E_CPU0_PE4_TX_DN<13>";
137"P5E_CPU0_PE4_TX_DN<15>";
138"P5E_CPU0_PE4_TX_DP<6>";
139"P5E_CPU0_PE4_TX_DN<7>";
140"P5E_CPU0_PE4_TX_DP<5>";
141"P5E_CPU0_PE4_TX_DN<5>";
142"P5E_CPU0_PE4_TX_DN<3>";
143"P5E_CPU0_PE4_TX_DN<0>";
144"P5E_CPU0_PE4_TX_DP<0>";
%"TAP"
"1","(-1900,150)","2","standard","I213";
;
CDS_LIB"standard"
BODY_TYPE"PLUMBING"
HDL_TAP"TRUE";
"B \NAC \NWC"1;
"S \NAC"
BN"0"144;
%"TAP"
"1","(-1900,350)","2","standard","I214";
;
CDS_LIB"standard"
BODY_TYPE"PLUMBING"
HDL_TAP"TRUE";
"B \NAC \NWC"1;
"S \NAC"
BN"1"93;
%"TAP"
"1","(-1650,200)","2","standard","I215";
;
CDS_LIB"standard"
BODY_TYPE"PLUMBING"
HDL_TAP"TRUE";
"B \NAC \NWC"2;
"S \NAC"
BN"0"143;
%"TAP"
"1","(-1650,400)","2","standard","I216";
;
CDS_LIB"standard"
BODY_TYPE"PLUMBING"
HDL_TAP"TRUE";
"B \NAC \NWC"2;
"S \NAC"
BN"1"92;
%"TAP"
"1","(-1900,750)","2","standard","I217";
;
CDS_LIB"standard"
BODY_TYPE"PLUMBING"
HDL_TAP"TRUE";
"B \NAC \NWC"1;
"S \NAC"
BN"3"90;
%"TAP"
"1","(-1900,550)","2","standard","I218";
;
CDS_LIB"standard"
BODY_TYPE"PLUMBING"
HDL_TAP"TRUE";
"B \NAC \NWC"1;
"S \NAC"
BN"2"94;
%"TAP"
"1","(-1900,950)","2","standard","I219";
;
CDS_LIB"standard"
BODY_TYPE"PLUMBING"
HDL_TAP"TRUE";
"B \NAC \NWC"1;
"S \NAC"
BN"4"89;
%"TAP"
"1","(-1650,600)","2","standard","I220";
;
CDS_LIB"standard"
BODY_TYPE"PLUMBING"
HDL_TAP"TRUE";
"B \NAC \NWC"2;
"S \NAC"
BN"2"91;
%"TAP"
"1","(-1650,800)","2","standard","I221";
;
CDS_LIB"standard"
BODY_TYPE"PLUMBING"
HDL_TAP"TRUE";
"B \NAC \NWC"2;
"S \NAC"
BN"3"142;
%"TAP"
"1","(-1650,1000)","2","standard","I222";
;
CDS_LIB"standard"
BODY_TYPE"PLUMBING"
HDL_TAP"TRUE";
"B \NAC \NWC"2;
"S \NAC"
BN"4"88;
%"TAP"
"1","(-1900,1150)","2","standard","I223";
;
CDS_LIB"standard"
BODY_TYPE"PLUMBING"
HDL_TAP"TRUE";
"B \NAC \NWC"1;
"S \NAC"
BN"5"140;
%"TAP"
"1","(-1900,1350)","2","standard","I224";
;
CDS_LIB"standard"
BODY_TYPE"PLUMBING"
HDL_TAP"TRUE";
"B \NAC \NWC"1;
"S \NAC"
BN"6"138;
%"TAP"
"1","(-1650,1200)","2","standard","I225";
;
CDS_LIB"standard"
BODY_TYPE"PLUMBING"
HDL_TAP"TRUE";
"B \NAC \NWC"2;
"S \NAC"
BN"5"141;
%"TAP"
"1","(-1650,1400)","2","standard","I226";
;
CDS_LIB"standard"
BODY_TYPE"PLUMBING"
HDL_TAP"TRUE";
"B \NAC \NWC"2;
"S \NAC"
BN"6"18;
%"TAP"
"1","(-1900,1550)","2","standard","I227";
;
CDS_LIB"standard"
BODY_TYPE"PLUMBING"
HDL_TAP"TRUE";
"B \NAC \NWC"1;
"S \NAC"
BN"7"87;
%"TAP"
"1","(-1650,1600)","2","standard","I228";
;
CDS_LIB"standard"
BODY_TYPE"PLUMBING"
HDL_TAP"TRUE";
"B \NAC \NWC"2;
"S \NAC"
BN"7"139;
%"Q_CAP_DIFFBUS"
"2","(-925,150)","2","pure_quanta","I229";
;
PART_NUMBER"SP_CH4221MEE01"
VALUE"DIFF BUS_0.22UF"
$LOCATION"C1579"
PIN_NAMES_ROTATE"TRUE"
CDS_LIB"pure_quanta"
CDS_LMAN_SYM_OUTLINE"-25,50,25,-50"
VOLTAGE"6.3V"
MATERIAL"X6S"
PACK_TYPE"C0201"
TOLERANCE"20%"
CDS_LOCATION"C1579"
$SEC"1"
CDS_SEC"1";
"2"
$PN"2"144;
"1"
$PN"1"103;
%"Q_CAP_DIFFBUS"
"2","(-925,200)","2","pure_quanta","I230";
;
PART_NUMBER"SP_CH4221MEE01"
VALUE"DIFF BUS_0.22UF"
$LOCATION"C1578"
PIN_NAMES_ROTATE"TRUE"
CDS_LIB"pure_quanta"
CDS_LMAN_SYM_OUTLINE"-25,50,25,-50"
VOLTAGE"6.3V"
MATERIAL"X6S"
PACK_TYPE"C0201"
TOLERANCE"20%"
CDS_LOCATION"C1578"
$SEC"1"
CDS_SEC"1";
"2"
$PN"2"143;
"1"
$PN"1"104;
%"Q_CAP_DIFFBUS"
"2","(-925,550)","2","pure_quanta","I231";
;
PART_NUMBER"SP_CH4221MEE01"
VALUE"DIFF BUS_0.22UF"
$LOCATION"C1575"
PIN_NAMES_ROTATE"TRUE"
CDS_LIB"pure_quanta"
CDS_LMAN_SYM_OUTLINE"-25,50,25,-50"
VOLTAGE"6.3V"
MATERIAL"X6S"
PACK_TYPE"C0201"
TOLERANCE"20%"
CDS_LOCATION"C1575"
$SEC"1"
CDS_SEC"1";
"2"
$PN"2"94;
"1"
$PN"1"107;
%"Q_CAP_DIFFBUS"
"2","(-925,600)","2","pure_quanta","I232";
;
PART_NUMBER"SP_CH4221MEE01"
VALUE"DIFF BUS_0.22UF"
$LOCATION"C1574"
PIN_NAMES_ROTATE"TRUE"
CDS_LIB"pure_quanta"
CDS_LMAN_SYM_OUTLINE"-25,50,25,-50"
VOLTAGE"6.3V"
MATERIAL"X6S"
PACK_TYPE"C0201"
TOLERANCE"20%"
CDS_LOCATION"C1574"
$SEC"1"
CDS_SEC"1";
"2"
$PN"2"91;
"1"
$PN"1"108;
%"Q_CAP_DIFFBUS"
"2","(-925,750)","2","pure_quanta","I233";
;
PART_NUMBER"SP_CH4221MEE01"
VALUE"DIFF BUS_0.22UF"
$LOCATION"C1573"
PIN_NAMES_ROTATE"TRUE"
CDS_LMAN_SYM_OUTLINE"-25,50,25,-50"
CDS_LIB"pure_quanta"
VOLTAGE"6.3V"
MATERIAL"X6S"
PACK_TYPE"C0201"
TOLERANCE"20%"
CDS_LOCATION"C1573"
$SEC"1"
CDS_SEC"1";
"2"
$PN"2"90;
"1"
$PN"1"109;
%"Q_CAP_DIFFBUS"
"2","(-925,800)","2","pure_quanta","I234";
;
PART_NUMBER"SP_CH4221MEE01"
VALUE"DIFF BUS_0.22UF"
$LOCATION"C1572"
PIN_NAMES_ROTATE"TRUE"
CDS_LMAN_SYM_OUTLINE"-25,50,25,-50"
CDS_LIB"pure_quanta"
VOLTAGE"6.3V"
MATERIAL"X6S"
PACK_TYPE"C0201"
TOLERANCE"20%"
CDS_LOCATION"C1572"
$SEC"1"
CDS_SEC"1";
"2"
$PN"2"142;
"1"
$PN"1"110;
%"Q_CAP_DIFFBUS"
"2","(-925,1000)","2","pure_quanta","I235";
;
PART_NUMBER"SP_CH4221MEE01"
VALUE"DIFF BUS_0.22UF"
$LOCATION"C1570"
PIN_NAMES_ROTATE"TRUE"
CDS_LIB"pure_quanta"
CDS_LMAN_SYM_OUTLINE"-25,50,25,-50"
VOLTAGE"6.3V"
MATERIAL"X6S"
PACK_TYPE"C0201"
TOLERANCE"20%"
CDS_LOCATION"C1570"
$SEC"1"
CDS_SEC"1";
"2"
$PN"2"88;
"1"
$PN"1"112;
%"Q_CAP_DIFFBUS"
"2","(-925,950)","2","pure_quanta","I236";
;
PART_NUMBER"SP_CH4221MEE01"
VALUE"DIFF BUS_0.22UF"
$LOCATION"C1571"
PIN_NAMES_ROTATE"TRUE"
CDS_LIB"pure_quanta"
CDS_LMAN_SYM_OUTLINE"-25,50,25,-50"
VOLTAGE"6.3V"
MATERIAL"X6S"
PACK_TYPE"C0201"
TOLERANCE"20%"
CDS_LOCATION"C1571"
$SEC"1"
CDS_SEC"1";
"2"
$PN"2"89;
"1"
$PN"1"111;
%"Q_CAP_DIFFBUS"
"2","(-925,1150)","2","pure_quanta","I237";
;
PART_NUMBER"SP_CH4221MEE01"
VALUE"DIFF BUS_0.22UF"
$LOCATION"C1569"
PIN_NAMES_ROTATE"TRUE"
CDS_LIB"pure_quanta"
CDS_LMAN_SYM_OUTLINE"-25,50,25,-50"
VOLTAGE"6.3V"
MATERIAL"X6S"
PACK_TYPE"C0201"
TOLERANCE"20%"
CDS_LOCATION"C1569"
$SEC"1"
CDS_SEC"1";
"2"
$PN"2"140;
"1"
$PN"1"17;
%"Q_CAP_DIFFBUS"
"2","(-925,1200)","2","pure_quanta","I238";
;
PART_NUMBER"SP_CH4221MEE01"
VALUE"DIFF BUS_0.22UF"
$LOCATION"C1568"
PIN_NAMES_ROTATE"TRUE"
CDS_LIB"pure_quanta"
CDS_LMAN_SYM_OUTLINE"-25,50,25,-50"
VOLTAGE"6.3V"
MATERIAL"X6S"
PACK_TYPE"C0201"
TOLERANCE"20%"
CDS_LOCATION"C1568"
$SEC"1"
CDS_SEC"1";
"2"
$PN"2"141;
"1"
$PN"1"113;
%"Q_CAP_DIFFBUS"
"2","(-925,1350)","2","pure_quanta","I239";
;
PART_NUMBER"SP_CH4221MEE01"
VALUE"DIFF BUS_0.22UF"
$LOCATION"C1567"
PIN_NAMES_ROTATE"TRUE"
CDS_LIB"pure_quanta"
CDS_LMAN_SYM_OUTLINE"-25,50,25,-50"
VOLTAGE"6.3V"
MATERIAL"X6S"
PACK_TYPE"C0201"
TOLERANCE"20%"
CDS_LOCATION"C1567"
$SEC"1"
CDS_SEC"1";
"2"
$PN"2"138;
"1"
$PN"1"95;
%"Q_CAP_DIFFBUS"
"2","(-925,1400)","2","pure_quanta","I240";
;
PART_NUMBER"SP_CH4221MEE01"
VALUE"DIFF BUS_0.22UF"
$LOCATION"C1566"
PIN_NAMES_ROTATE"TRUE"
CDS_LIB"pure_quanta"
CDS_LMAN_SYM_OUTLINE"-25,50,25,-50"
VOLTAGE"6.3V"
MATERIAL"X6S"
PACK_TYPE"C0201"
TOLERANCE"20%"
CDS_LOCATION"C1566"
$SEC"1"
CDS_SEC"1";
"2"
$PN"2"18;
"1"
$PN"1"96;
%"Q_CAP_DIFFBUS"
"2","(-925,1550)","2","pure_quanta","I241";
;
PART_NUMBER"SP_CH4221MEE01"
VALUE"DIFF BUS_0.22UF"
$LOCATION"C1565"
PIN_NAMES_ROTATE"TRUE"
CDS_LIB"pure_quanta"
CDS_LMAN_SYM_OUTLINE"-25,50,25,-50"
VOLTAGE"6.3V"
MATERIAL"X6S"
PACK_TYPE"C0201"
TOLERANCE"20%"
CDS_LOCATION"C1565"
$SEC"1"
CDS_SEC"1";
"2"
$PN"2"87;
"1"
$PN"1"97;
%"Q_CAP_DIFFBUS"
"2","(-925,1600)","2","pure_quanta","I242";
;
PART_NUMBER"SP_CH4221MEE01"
VALUE"DIFF BUS_0.22UF"
$LOCATION"C1564"
PIN_NAMES_ROTATE"TRUE"
CDS_LMAN_SYM_OUTLINE"-25,50,25,-50"
CDS_LIB"pure_quanta"
VOLTAGE"6.3V"
MATERIAL"X6S"
PACK_TYPE"C0201"
TOLERANCE"20%"
CDS_LOCATION"C1564"
$SEC"1"
CDS_SEC"1";
"2"
$PN"2"139;
"1"
$PN"1"98;
%"TAP"
"1","(-1900,2125)","2","standard","I243";
;
CDS_LIB"standard"
BODY_TYPE"PLUMBING"
HDL_TAP"TRUE";
"B \NAC \NWC"4;
"S \NAC"
BN"8"127;
%"TAP"
"1","(-1900,2325)","2","standard","I244";
;
CDS_LIB"standard"
BODY_TYPE"PLUMBING"
HDL_TAP"TRUE";
"B \NAC \NWC"4;
"S \NAC"
BN"9"129;
%"TAP"
"1","(-1900,2525)","2","standard","I245";
;
CDS_LIB"standard"
BODY_TYPE"PLUMBING"
HDL_TAP"TRUE";
"B \NAC \NWC"4;
"S \NAC"
BN"10"85;
%"TAP"
"1","(-1650,2175)","2","standard","I246";
;
CDS_LIB"standard"
BODY_TYPE"PLUMBING"
HDL_TAP"TRUE";
"B \NAC \NWC"3;
"S \NAC"
BN"8"131;
%"TAP"
"1","(-1650,2375)","2","standard","I247";
;
CDS_LIB"standard"
BODY_TYPE"PLUMBING"
HDL_TAP"TRUE";
"B \NAC \NWC"3;
"S \NAC"
BN"9"133;
%"TAP"
"1","(-1900,2725)","2","standard","I248";
;
CDS_LIB"standard"
BODY_TYPE"PLUMBING"
HDL_TAP"TRUE";
"B \NAC \NWC"4;
"S \NAC"
BN"11"128;
%"TAP"
"1","(-1900,2925)","2","standard","I249";
;
CDS_LIB"standard"
BODY_TYPE"PLUMBING"
HDL_TAP"TRUE";
"B \NAC \NWC"4;
"S \NAC"
BN"12"130;
%"TAP"
"1","(-1650,2775)","2","standard","I250";
;
CDS_LIB"standard"
BODY_TYPE"PLUMBING"
HDL_TAP"TRUE";
"B \NAC \NWC"3;
"S \NAC"
BN"11"124;
%"TAP"
"1","(-1650,2575)","2","standard","I251";
;
CDS_LIB"standard"
BODY_TYPE"PLUMBING"
HDL_TAP"TRUE";
"B \NAC \NWC"3;
"S \NAC"
BN"10"134;
%"TAP"
"1","(-1650,2975)","2","standard","I252";
;
CDS_LIB"standard"
BODY_TYPE"PLUMBING"
HDL_TAP"TRUE";
"B \NAC \NWC"3;
"S \NAC"
BN"12"132;
%"TAP"
"1","(-1900,3325)","2","standard","I253";
;
CDS_LIB"standard"
BODY_TYPE"PLUMBING"
HDL_TAP"TRUE";
"B \NAC \NWC"4;
"S \NAC"
BN"14"125;
%"TAP"
"1","(-1900,3125)","2","standard","I254";
;
CDS_LIB"standard"
BODY_TYPE"PLUMBING"
HDL_TAP"TRUE";
"B \NAC \NWC"4;
"S \NAC"
BN"13"83;
%"TAP"
"1","(-1900,3525)","2","standard","I255";
;
CDS_LIB"standard"
BODY_TYPE"PLUMBING"
HDL_TAP"TRUE";
"B \NAC \NWC"4;
"S \NAC"
BN"15"126;
%"TAP"
"1","(-1650,3175)","2","standard","I256";
;
CDS_LIB"standard"
BODY_TYPE"PLUMBING"
HDL_TAP"TRUE";
"B \NAC \NWC"3;
"S \NAC"
BN"13"136;
%"TAP"
"1","(-1650,3575)","2","standard","I257";
;
CDS_LIB"standard"
BODY_TYPE"PLUMBING"
HDL_TAP"TRUE";
"B \NAC \NWC"3;
"S \NAC"
BN"15"137;
%"TAP"
"1","(-1650,3375)","2","standard","I258";
;
CDS_LIB"standard"
BODY_TYPE"PLUMBING"
HDL_TAP"TRUE";
"B \NAC \NWC"3;
"S \NAC"
BN"14"135;
%"Q_CAP_DIFFBUS"
"2","(-925,2125)","2","pure_quanta","I259";
;
PART_NUMBER"SP_CH4221MEE01"
VALUE"DIFF BUS_0.22UF"
$LOCATION"C1563"
CDS_LMAN_SYM_OUTLINE"-25,50,25,-50"
CDS_LIB"pure_quanta"
PIN_NAMES_ROTATE"TRUE"
VOLTAGE"6.3V"
MATERIAL"X6S"
PACK_TYPE"C0201"
TOLERANCE"20%"
CDS_LOCATION"C1563"
$SEC"1"
CDS_SEC"1";
"2"
$PN"2"127;
"1"
$PN"1"99;
%"Q_CAP_DIFFBUS"
"2","(-925,2175)","2","pure_quanta","I260";
;
PART_NUMBER"SP_CH4221MEE01"
VALUE"DIFF BUS_0.22UF"
$LOCATION"C1794"
CDS_LMAN_SYM_OUTLINE"-25,50,25,-50"
CDS_LIB"pure_quanta"
PIN_NAMES_ROTATE"TRUE"
VOLTAGE"6.3V"
MATERIAL"X6S"
PACK_TYPE"C0201"
TOLERANCE"20%"
CDS_LOCATION"C1794"
$SEC"1"
CDS_SEC"1";
"2"
$PN"2"131;
"1"
$PN"1"100;
%"Q_CAP_DIFFBUS"
"2","(-925,2325)","2","pure_quanta","I261";
;
PART_NUMBER"SP_CH4221MEE01"
VALUE"DIFF BUS_0.22UF"
$LOCATION"C1793"
CDS_LMAN_SYM_OUTLINE"-25,50,25,-50"
CDS_LIB"pure_quanta"
PIN_NAMES_ROTATE"TRUE"
VOLTAGE"6.3V"
MATERIAL"X6S"
PACK_TYPE"C0201"
TOLERANCE"20%"
CDS_LOCATION"C1793"
$SEC"1"
CDS_SEC"1";
"2"
$PN"2"129;
"1"
$PN"1"86;
%"Q_CAP_DIFFBUS"
"2","(-925,2375)","2","pure_quanta","I262";
;
PART_NUMBER"SP_CH4221MEE01"
VALUE"DIFF BUS_0.22UF"
$LOCATION"C1560"
CDS_LIB"pure_quanta"
CDS_LMAN_SYM_OUTLINE"-25,50,25,-50"
PIN_NAMES_ROTATE"TRUE"
VOLTAGE"6.3V"
MATERIAL"X6S"
PACK_TYPE"C0201"
TOLERANCE"20%"
CDS_LOCATION"C1560"
$SEC"1"
CDS_SEC"1";
"2"
$PN"2"133;
"1"
$PN"1"121;
%"Q_CAP_DIFFBUS"
"2","(-925,2525)","2","pure_quanta","I263";
;
PART_NUMBER"SP_CH4221MEE01"
VALUE"DIFF BUS_0.22UF"
$LOCATION"C1559"
CDS_LMAN_SYM_OUTLINE"-25,50,25,-50"
CDS_LIB"pure_quanta"
PIN_NAMES_ROTATE"TRUE"
VOLTAGE"6.3V"
MATERIAL"X6S"
PACK_TYPE"C0201"
TOLERANCE"20%"
CDS_LOCATION"C1559"
$SEC"1"
CDS_SEC"1";
"2"
$PN"2"85;
"1"
$PN"1"114;
%"Q_CAP_DIFFBUS"
"2","(-925,2575)","2","pure_quanta","I264";
;
PART_NUMBER"SP_CH4221MEE01"
VALUE"DIFF BUS_0.22UF"
$LOCATION"C1558"
CDS_LMAN_SYM_OUTLINE"-25,50,25,-50"
CDS_LIB"pure_quanta"
PIN_NAMES_ROTATE"TRUE"
VOLTAGE"6.3V"
MATERIAL"X6S"
PACK_TYPE"C0201"
TOLERANCE"20%"
CDS_LOCATION"C1558"
$SEC"1"
CDS_SEC"1";
"2"
$PN"2"134;
"1"
$PN"1"115;
%"Q_CAP_DIFFBUS"
"2","(-925,2775)","2","pure_quanta","I265";
;
PART_NUMBER"SP_CH4221MEE01"
VALUE"DIFF BUS_0.22UF"
$LOCATION"C1556"
CDS_LIB"pure_quanta"
CDS_LMAN_SYM_OUTLINE"-25,50,25,-50"
PIN_NAMES_ROTATE"TRUE"
VOLTAGE"6.3V"
MATERIAL"X6S"
PACK_TYPE"C0201"
TOLERANCE"20%"
CDS_LOCATION"C1556"
$SEC"1"
CDS_SEC"1";
"2"
$PN"2"124;
"1"
$PN"1"116;
%"Q_CAP_DIFFBUS"
"2","(-925,2725)","2","pure_quanta","I266";
;
PART_NUMBER"SP_CH4221MEE01"
VALUE"DIFF BUS_0.22UF"
$LOCATION"C1557"
CDS_LIB"pure_quanta"
CDS_LMAN_SYM_OUTLINE"-25,50,25,-50"
PIN_NAMES_ROTATE"TRUE"
VOLTAGE"6.3V"
MATERIAL"X6S"
PACK_TYPE"C0201"
TOLERANCE"20%"
CDS_LOCATION"C1557"
$SEC"1"
CDS_SEC"1";
"2"
$PN"2"128;
"1"
$PN"1"84;
%"Q_CAP_DIFFBUS"
"2","(-925,2925)","2","pure_quanta","I267";
;
PART_NUMBER"SP_CH4221MEE01"
VALUE"DIFF BUS_0.22UF"
$LOCATION"C1555"
CDS_LMAN_SYM_OUTLINE"-25,50,25,-50"
CDS_LIB"pure_quanta"
PIN_NAMES_ROTATE"TRUE"
VOLTAGE"6.3V"
MATERIAL"X6S"
PACK_TYPE"C0201"
TOLERANCE"20%"
CDS_LOCATION"C1555"
$SEC"1"
CDS_SEC"1";
"2"
$PN"2"130;
"1"
$PN"1"117;
%"Q_CAP_DIFFBUS"
"2","(-925,2975)","2","pure_quanta","I268";
;
PART_NUMBER"SP_CH4221MEE01"
VALUE"DIFF BUS_0.22UF"
$LOCATION"C1554"
CDS_LMAN_SYM_OUTLINE"-25,50,25,-50"
CDS_LIB"pure_quanta"
PIN_NAMES_ROTATE"TRUE"
VOLTAGE"6.3V"
MATERIAL"X6S"
PACK_TYPE"C0201"
TOLERANCE"20%"
CDS_LOCATION"C1554"
$SEC"1"
CDS_SEC"1";
"2"
$PN"2"132;
"1"
$PN"1"118;
%"Q_CAP_DIFFBUS"
"2","(-925,3125)","2","pure_quanta","I269";
;
PART_NUMBER"SP_CH4221MEE01"
VALUE"DIFF BUS_0.22UF"
$LOCATION"C1553"
CDS_LMAN_SYM_OUTLINE"-25,50,25,-50"
CDS_LIB"pure_quanta"
PIN_NAMES_ROTATE"TRUE"
VOLTAGE"6.3V"
MATERIAL"X6S"
PACK_TYPE"C0201"
TOLERANCE"20%"
CDS_LOCATION"C1553"
$SEC"1"
CDS_SEC"1";
"2"
$PN"2"83;
"1"
$PN"1"119;
%"Q_CAP_DIFFBUS"
"2","(-925,3175)","2","pure_quanta","I270";
;
PART_NUMBER"SP_CH4221MEE01"
VALUE"DIFF BUS_0.22UF"
$LOCATION"C1552"
CDS_LMAN_SYM_OUTLINE"-25,50,25,-50"
CDS_LIB"pure_quanta"
PIN_NAMES_ROTATE"TRUE"
VOLTAGE"6.3V"
MATERIAL"X6S"
PACK_TYPE"C0201"
TOLERANCE"20%"
CDS_LOCATION"C1552"
$SEC"1"
CDS_SEC"1";
"2"
$PN"2"136;
"1"
$PN"1"120;
%"Q_CAP_DIFFBUS"
"2","(-925,3325)","2","pure_quanta","I271";
;
PART_NUMBER"SP_CH4221MEE01"
VALUE"DIFF BUS_0.22UF"
$LOCATION"C1792"
CDS_LMAN_SYM_OUTLINE"-25,50,25,-50"
CDS_LIB"pure_quanta"
PIN_NAMES_ROTATE"TRUE"
VOLTAGE"6.3V"
MATERIAL"X6S"
PACK_TYPE"C0201"
TOLERANCE"20%"
CDS_LOCATION"C1792"
$SEC"1"
CDS_SEC"1";
"2"
$PN"2"125;
"1"
$PN"1"122;
%"Q_CAP_DIFFBUS"
"2","(-925,3375)","2","pure_quanta","I272";
;
PART_NUMBER"SP_CH4221MEE01"
VALUE"DIFF BUS_0.22UF"
$LOCATION"C1550"
CDS_LMAN_SYM_OUTLINE"-25,50,25,-50"
CDS_LIB"pure_quanta"
PIN_NAMES_ROTATE"TRUE"
VOLTAGE"6.3V"
MATERIAL"X6S"
PACK_TYPE"C0201"
TOLERANCE"20%"
CDS_LOCATION"C1550"
$SEC"1"
CDS_SEC"1";
"2"
$PN"2"135;
"1"
$PN"1"123;
%"Q_CAP_DIFFBUS"
"2","(-925,3575)","2","pure_quanta","I273";
;
PART_NUMBER"SP_CH4221MEE01"
PACK_TYPE"C0201"
VALUE"DIFF BUS_0.22UF"
VOLTAGE"6.3V"
MATERIAL"X6S"
TOLERANCE"20%"
$LOCATION"C1548"
CDS_LIB"pure_quanta"
CDS_LMAN_SYM_OUTLINE"-25,50,25,-50"
PIN_NAMES_ROTATE"TRUE"
CDS_LOCATION"C1548"
$SEC"1"
CDS_SEC"1";
"2"
$PN"2"137;
"1"
$PN"1"102;
%"Q_CAP_DIFFBUS"
"2","(-925,3525)","2","pure_quanta","I274";
;
PART_NUMBER"SP_CH4221MEE01"
VALUE"DIFF BUS_0.22UF"
$LOCATION"C1549"
CDS_LMAN_SYM_OUTLINE"-25,50,25,-50"
CDS_LIB"pure_quanta"
PIN_NAMES_ROTATE"TRUE"
VOLTAGE"6.3V"
MATERIAL"X6S"
PACK_TYPE"C0201"
TOLERANCE"20%"
CDS_LOCATION"C1549"
$SEC"1"
CDS_SEC"1";
"2"
$PN"2"126;
"1"
$PN"1"101;
%"TAP"
"1","(-375,200)","0","standard","I275";
;
CDS_LIB"standard"
BODY_TYPE"PLUMBING"
HDL_TAP"TRUE";
"B \NAC \NWC"7;
"S \NAC"
BN"0"104;
%"TAP"
"1","(-175,150)","0","standard","I276";
;
CDS_LIB"standard"
BODY_TYPE"PLUMBING"
HDL_TAP"TRUE";
"B \NAC \NWC"8;
"S \NAC"
BN"0"103;
%"TAP"
"1","(-175,350)","0","standard","I277";
;
CDS_LIB"standard"
BODY_TYPE"PLUMBING"
HDL_TAP"TRUE";
"B \NAC \NWC"8;
"S \NAC"
BN"1"105;
%"TAP"
"1","(-375,400)","0","standard","I278";
;
CDS_LIB"standard"
BODY_TYPE"PLUMBING"
HDL_TAP"TRUE";
"B \NAC \NWC"7;
"S \NAC"
BN"1"106;
%"TAP"
"1","(-375,600)","0","standard","I279";
;
CDS_LIB"standard"
BODY_TYPE"PLUMBING"
HDL_TAP"TRUE";
"B \NAC \NWC"7;
"S \NAC"
BN"2"108;
%"TAP"
"1","(-175,550)","0","standard","I280";
;
CDS_LIB"standard"
BODY_TYPE"PLUMBING"
HDL_TAP"TRUE";
"B \NAC \NWC"8;
"S \NAC"
BN"2"107;
%"TAP"
"1","(-175,750)","0","standard","I281";
;
CDS_LIB"standard"
BODY_TYPE"PLUMBING"
HDL_TAP"TRUE";
"B \NAC \NWC"8;
"S \NAC"
BN"3"109;
%"TAP"
"1","(-375,1000)","0","standard","I282";
;
CDS_LIB"standard"
BODY_TYPE"PLUMBING"
HDL_TAP"TRUE";
"B \NAC \NWC"7;
"S \NAC"
BN"4"112;
%"TAP"
"1","(-375,800)","0","standard","I283";
;
CDS_LIB"standard"
BODY_TYPE"PLUMBING"
HDL_TAP"TRUE";
"B \NAC \NWC"7;
"S \NAC"
BN"3"110;
%"TAP"
"1","(-175,950)","0","standard","I284";
;
CDS_LIB"standard"
BODY_TYPE"PLUMBING"
HDL_TAP"TRUE";
"B \NAC \NWC"8;
"S \NAC"
BN"4"111;
%"TAP"
"1","(-375,1200)","0","standard","I285";
;
CDS_LIB"standard"
BODY_TYPE"PLUMBING"
HDL_TAP"TRUE";
"B \NAC \NWC"7;
"S \NAC"
BN"5"113;
%"TAP"
"1","(-175,1150)","0","standard","I286";
;
CDS_LIB"standard"
BODY_TYPE"PLUMBING"
HDL_TAP"TRUE";
"B \NAC \NWC"8;
"S \NAC"
BN"5"17;
%"TAP"
"1","(-375,1400)","0","standard","I287";
;
CDS_LIB"standard"
BODY_TYPE"PLUMBING"
HDL_TAP"TRUE";
"B \NAC \NWC"7;
"S \NAC"
BN"6"96;
%"TAP"
"1","(-175,1350)","0","standard","I288";
;
CDS_LIB"standard"
BODY_TYPE"PLUMBING"
HDL_TAP"TRUE";
"B \NAC \NWC"8;
"S \NAC"
BN"6"95;
%"TAP"
"1","(-375,1600)","0","standard","I289";
;
CDS_LIB"standard"
BODY_TYPE"PLUMBING"
HDL_TAP"TRUE";
"B \NAC \NWC"7;
"S \NAC"
BN"7"98;
%"TAP"
"1","(-175,1550)","0","standard","I290";
;
CDS_LIB"standard"
BODY_TYPE"PLUMBING"
HDL_TAP"TRUE";
"B \NAC \NWC"8;
"S \NAC"
BN"7"97;
%"TAP"
"1","(-375,2175)","0","standard","I293";
;
CDS_LIB"standard"
BODY_TYPE"PLUMBING"
HDL_TAP"TRUE";
"B \NAC \NWC"5;
"S \NAC"
BN"8"100;
%"TAP"
"1","(-175,2125)","0","standard","I294";
;
CDS_LIB"standard"
BODY_TYPE"PLUMBING"
HDL_TAP"TRUE";
"B \NAC \NWC"6;
"S \NAC"
BN"8"99;
%"TAP"
"1","(-375,2375)","0","standard","I295";
;
CDS_LIB"standard"
BODY_TYPE"PLUMBING"
HDL_TAP"TRUE";
"B \NAC \NWC"5;
"S \NAC"
BN"9"121;
%"TAP"
"1","(-175,2325)","0","standard","I296";
;
CDS_LIB"standard"
BODY_TYPE"PLUMBING"
HDL_TAP"TRUE";
"B \NAC \NWC"6;
"S \NAC"
BN"9"86;
%"TAP"
"1","(-175,2525)","0","standard","I297";
;
CDS_LIB"standard"
BODY_TYPE"PLUMBING"
HDL_TAP"TRUE";
"B \NAC \NWC"6;
"S \NAC"
BN"10"114;
%"TAP"
"1","(-375,2775)","0","standard","I298";
;
CDS_LIB"standard"
BODY_TYPE"PLUMBING"
HDL_TAP"TRUE";
"B \NAC \NWC"5;
"S \NAC"
BN"11"116;
%"TAP"
"1","(-375,2575)","0","standard","I299";
;
CDS_LIB"standard"
BODY_TYPE"PLUMBING"
HDL_TAP"TRUE";
"B \NAC \NWC"5;
"S \NAC"
BN"10"115;
%"TAP"
"1","(-175,2725)","0","standard","I300";
;
CDS_LIB"standard"
BODY_TYPE"PLUMBING"
HDL_TAP"TRUE";
"B \NAC \NWC"6;
"S \NAC"
BN"11"84;
%"TAP"
"1","(-375,2975)","0","standard","I301";
;
CDS_LIB"standard"
BODY_TYPE"PLUMBING"
HDL_TAP"TRUE";
"B \NAC \NWC"5;
"S \NAC"
BN"12"118;
%"TAP"
"1","(-175,2925)","0","standard","I302";
;
CDS_LIB"standard"
BODY_TYPE"PLUMBING"
HDL_TAP"TRUE";
"B \NAC \NWC"6;
"S \NAC"
BN"12"117;
%"TAP"
"1","(-375,3175)","0","standard","I303";
;
CDS_LIB"standard"
BODY_TYPE"PLUMBING"
HDL_TAP"TRUE";
"B \NAC \NWC"5;
"S \NAC"
BN"13"120;
%"TAP"
"1","(-175,3325)","0","standard","I304";
;
CDS_LIB"standard"
BODY_TYPE"PLUMBING"
HDL_TAP"TRUE";
"B \NAC \NWC"6;
"S \NAC"
BN"14"122;
%"TAP"
"1","(-175,3125)","0","standard","I305";
;
CDS_LIB"standard"
BODY_TYPE"PLUMBING"
HDL_TAP"TRUE";
"B \NAC \NWC"6;
"S \NAC"
BN"13"119;
%"TAP"
"1","(-375,3375)","0","standard","I306";
;
CDS_LIB"standard"
BODY_TYPE"PLUMBING"
HDL_TAP"TRUE";
"B \NAC \NWC"5;
"S \NAC"
BN"14"123;
%"TAP"
"1","(-375,3575)","0","standard","I307";
;
CDS_LIB"standard"
BODY_TYPE"PLUMBING"
HDL_TAP"TRUE";
"B \NAC \NWC"5;
"S \NAC"
BN"15"102;
%"TAP"
"1","(-175,3525)","0","standard","I308";
;
CDS_LIB"standard"
BODY_TYPE"PLUMBING"
HDL_TAP"TRUE";
"B \NAC \NWC"6;
"S \NAC"
BN"15"101;
%"Q_CAP_DIFFBUS"
"2","(-925,350)","2","pure_quanta","I311";
;
PART_NUMBER"SP_CH4221MEE01"
VALUE"DIFF BUS_0.22UF"
$LOCATION"C1577"
PIN_NAMES_ROTATE"TRUE"
CDS_LIB"pure_quanta"
CDS_LMAN_SYM_OUTLINE"-25,50,25,-50"
VOLTAGE"6.3V"
MATERIAL"X6S"
PACK_TYPE"C0201"
TOLERANCE"20%"
CDS_LOCATION"C1577"
$SEC"1"
CDS_SEC"1";
"2"
$PN"2"93;
"1"
$PN"1"105;
%"Q_CAP_DIFFBUS"
"2","(-925,400)","2","pure_quanta","I312";
;
PART_NUMBER"SP_CH4221MEE01"
VALUE"DIFF BUS_0.22UF"
$LOCATION"C1576"
PIN_NAMES_ROTATE"TRUE"
CDS_LMAN_SYM_OUTLINE"-25,50,25,-50"
CDS_LIB"pure_quanta"
VOLTAGE"6.3V"
MATERIAL"X6S"
PACK_TYPE"C0201"
TOLERANCE"20%"
CDS_LOCATION"C1576"
$SEC"1"
CDS_SEC"1";
"2"
$PN"2"92;
"1"
$PN"1"106;
%"TAP"
"1","(2600,150)","2","standard","I317";
;
CDS_LIB"standard"
BODY_TYPE"PLUMBING"
HDL_TAP"TRUE";
"B \NAC \NWC"9;
"S \NAC"
BN"0"82;
%"TAP"
"1","(2600,350)","2","standard","I318";
;
CDS_LIB"standard"
BODY_TYPE"PLUMBING"
HDL_TAP"TRUE";
"B \NAC \NWC"9;
"S \NAC"
BN"1"81;
%"TAP"
"1","(2850,200)","2","standard","I319";
;
CDS_LIB"standard"
BODY_TYPE"PLUMBING"
HDL_TAP"TRUE";
"B \NAC \NWC"10;
"S \NAC"
BN"0"77;
%"TAP"
"1","(2850,400)","2","standard","I320";
;
CDS_LIB"standard"
BODY_TYPE"PLUMBING"
HDL_TAP"TRUE";
"B \NAC \NWC"10;
"S \NAC"
BN"1"76;
%"TAP"
"1","(2600,550)","2","standard","I321";
;
CDS_LIB"standard"
BODY_TYPE"PLUMBING"
HDL_TAP"TRUE";
"B \NAC \NWC"9;
"S \NAC"
BN"2"80;
%"TAP"
"1","(2600,750)","2","standard","I322";
;
CDS_LIB"standard"
BODY_TYPE"PLUMBING"
HDL_TAP"TRUE";
"B \NAC \NWC"9;
"S \NAC"
BN"3"78;
%"TAP"
"1","(2600,950)","2","standard","I323";
;
CDS_LIB"standard"
BODY_TYPE"PLUMBING"
HDL_TAP"TRUE";
"B \NAC \NWC"9;
"S \NAC"
BN"4"79;
%"TAP"
"1","(2850,600)","2","standard","I324";
;
CDS_LIB"standard"
BODY_TYPE"PLUMBING"
HDL_TAP"TRUE";
"B \NAC \NWC"10;
"S \NAC"
BN"2"75;
%"TAP"
"1","(2850,800)","2","standard","I325";
;
CDS_LIB"standard"
BODY_TYPE"PLUMBING"
HDL_TAP"TRUE";
"B \NAC \NWC"10;
"S \NAC"
BN"3"74;
%"TAP"
"1","(2850,1000)","2","standard","I326";
;
CDS_LIB"standard"
BODY_TYPE"PLUMBING"
HDL_TAP"TRUE";
"B \NAC \NWC"10;
"S \NAC"
BN"4"73;
%"TAP"
"1","(2600,1150)","2","standard","I327";
;
CDS_LIB"standard"
BODY_TYPE"PLUMBING"
HDL_TAP"TRUE";
"B \NAC \NWC"9;
"S \NAC"
BN"5"72;
%"TAP"
"1","(2600,1350)","2","standard","I328";
;
CDS_LIB"standard"
BODY_TYPE"PLUMBING"
HDL_TAP"TRUE";
"B \NAC \NWC"9;
"S \NAC"
BN"6"71;
%"TAP"
"1","(2850,1200)","2","standard","I329";
;
CDS_LIB"standard"
BODY_TYPE"PLUMBING"
HDL_TAP"TRUE";
"B \NAC \NWC"10;
"S \NAC"
BN"5"70;
%"TAP"
"1","(2850,1400)","2","standard","I330";
;
CDS_LIB"standard"
BODY_TYPE"PLUMBING"
HDL_TAP"TRUE";
"B \NAC \NWC"10;
"S \NAC"
BN"6"69;
%"TAP"
"1","(2600,1550)","2","standard","I331";
;
CDS_LIB"standard"
BODY_TYPE"PLUMBING"
HDL_TAP"TRUE";
"B \NAC \NWC"9;
"S \NAC"
BN"7"33;
%"TAP"
"1","(2850,1600)","2","standard","I332";
;
CDS_LIB"standard"
BODY_TYPE"PLUMBING"
HDL_TAP"TRUE";
"B \NAC \NWC"10;
"S \NAC"
BN"7"34;
%"Q_CAP_DIFFBUS"
"2","(3575,200)","2","pure_quanta","I333";
;
PART_NUMBER"SP_CH4221MEE01"
VALUE"DIFF BUS_0.22UF"
$LOCATION"C836"
PIN_NAMES_ROTATE"TRUE"
CDS_LIB"pure_quanta"
CDS_LMAN_SYM_OUTLINE"-25,50,25,-50"
VOLTAGE"6.3V"
MATERIAL"X6S"
PACK_TYPE"C0201"
TOLERANCE"20%"
$LOCATION"C836"
CDS_LOCATION"C836"
$SEC"1"
CDS_SEC"1";
"2"
$PN"2"77;
"1"
$PN"1"52;
%"Q_CAP_DIFFBUS"
"2","(3575,150)","2","pure_quanta","I334";
;
PART_NUMBER"SP_CH4221MEE01"
VALUE"DIFF BUS_0.22UF"
$LOCATION"C837"
PIN_NAMES_ROTATE"TRUE"
CDS_LIB"pure_quanta"
CDS_LMAN_SYM_OUTLINE"-25,50,25,-50"
VOLTAGE"6.3V"
MATERIAL"X6S"
PACK_TYPE"C0201"
TOLERANCE"20%"
$LOCATION"C837"
CDS_LOCATION"C837"
$SEC"1"
CDS_SEC"1";
"2"
$PN"2"82;
"1"
$PN"1"29;
%"Q_CAP_DIFFBUS"
"2","(3575,400)","2","pure_quanta","I335";
;
PART_NUMBER"SP_CH4221MEE01"
VALUE"DIFF BUS_0.22UF"
$LOCATION"C834"
PIN_NAMES_ROTATE"TRUE"
CDS_LMAN_SYM_OUTLINE"-25,50,25,-50"
CDS_LIB"pure_quanta"
VOLTAGE"6.3V"
MATERIAL"X6S"
PACK_TYPE"C0201"
TOLERANCE"20%"
$LOCATION"C834"
CDS_LOCATION"C834"
$SEC"1"
CDS_SEC"1";
"2"
$PN"2"76;
"1"
$PN"1"51;
%"Q_CAP_DIFFBUS"
"2","(3575,350)","2","pure_quanta","I336";
;
PART_NUMBER"SP_CH4221MEE01"
VALUE"DIFF BUS_0.22UF"
$LOCATION"C835"
PIN_NAMES_ROTATE"TRUE"
CDS_LIB"pure_quanta"
CDS_LMAN_SYM_OUTLINE"-25,50,25,-50"
VOLTAGE"6.3V"
MATERIAL"X6S"
PACK_TYPE"C0201"
TOLERANCE"20%"
$LOCATION"C835"
CDS_LOCATION"C835"
$SEC"1"
CDS_SEC"1";
"2"
$PN"2"81;
"1"
$PN"1"30;
%"Q_CAP_DIFFBUS"
"2","(3575,750)","2","pure_quanta","I337";
;
PART_NUMBER"SP_CH4221MEE01"
VALUE"DIFF BUS_0.22UF"
$LOCATION"C831"
PIN_NAMES_ROTATE"TRUE"
CDS_LMAN_SYM_OUTLINE"-25,50,25,-50"
CDS_LIB"pure_quanta"
VOLTAGE"6.3V"
MATERIAL"X6S"
PACK_TYPE"C0201"
TOLERANCE"20%"
$LOCATION"C831"
CDS_LOCATION"C831"
$SEC"1"
CDS_SEC"1";
"2"
$PN"2"78;
"1"
$PN"1"32;
%"Q_CAP_DIFFBUS"
"2","(3575,600)","2","pure_quanta","I338";
;
PART_NUMBER"SP_CH4221MEE01"
VALUE"DIFF BUS_0.22UF"
$LOCATION"C832"
PIN_NAMES_ROTATE"TRUE"
CDS_LIB"pure_quanta"
CDS_LMAN_SYM_OUTLINE"-25,50,25,-50"
VOLTAGE"6.3V"
MATERIAL"X6S"
PACK_TYPE"C0201"
TOLERANCE"20%"
$LOCATION"C832"
CDS_LOCATION"C832"
$SEC"1"
CDS_SEC"1";
"2"
$PN"2"75;
"1"
$PN"1"50;
%"Q_CAP_DIFFBUS"
"2","(3575,550)","2","pure_quanta","I339";
;
PART_NUMBER"SP_CH4221MEE01"
VALUE"DIFF BUS_0.22UF"
$LOCATION"C833"
PIN_NAMES_ROTATE"TRUE"
CDS_LIB"pure_quanta"
CDS_LMAN_SYM_OUTLINE"-25,50,25,-50"
VOLTAGE"6.3V"
MATERIAL"X6S"
PACK_TYPE"C0201"
TOLERANCE"20%"
$LOCATION"C833"
CDS_LOCATION"C833"
$SEC"1"
CDS_SEC"1";
"2"
$PN"2"80;
"1"
$PN"1"31;
%"Q_CAP_DIFFBUS"
"2","(3575,1000)","2","pure_quanta","I340";
;
PART_NUMBER"SP_CH4221MEE01"
VALUE"DIFF BUS_0.22UF"
$LOCATION"C828"
PIN_NAMES_ROTATE"TRUE"
CDS_LIB"pure_quanta"
CDS_LMAN_SYM_OUTLINE"-25,50,25,-50"
VOLTAGE"6.3V"
MATERIAL"X6S"
PACK_TYPE"C0201"
TOLERANCE"20%"
$LOCATION"C828"
CDS_LOCATION"C828"
$SEC"1"
CDS_SEC"1";
"2"
$PN"2"73;
"1"
$PN"1"48;
%"Q_CAP_DIFFBUS"
"2","(3575,800)","2","pure_quanta","I341";
;
PART_NUMBER"SP_CH4221MEE01"
VALUE"DIFF BUS_0.22UF"
$LOCATION"C830"
PIN_NAMES_ROTATE"TRUE"
CDS_LMAN_SYM_OUTLINE"-25,50,25,-50"
CDS_LIB"pure_quanta"
VOLTAGE"6.3V"
MATERIAL"X6S"
PACK_TYPE"C0201"
TOLERANCE"20%"
$LOCATION"C830"
CDS_LOCATION"C830"
$SEC"1"
CDS_SEC"1";
"2"
$PN"2"74;
"1"
$PN"1"49;
%"Q_CAP_DIFFBUS"
"2","(3575,950)","2","pure_quanta","I342";
;
PART_NUMBER"SP_CH4221MEE01"
VALUE"DIFF BUS_0.22UF"
$LOCATION"C829"
PIN_NAMES_ROTATE"TRUE"
CDS_LIB"pure_quanta"
CDS_LMAN_SYM_OUTLINE"-25,50,25,-50"
VOLTAGE"6.3V"
MATERIAL"X6S"
PACK_TYPE"C0201"
TOLERANCE"20%"
$LOCATION"C829"
CDS_LOCATION"C829"
$SEC"1"
CDS_SEC"1";
"2"
$PN"2"79;
"1"
$PN"1"36;
%"Q_CAP_DIFFBUS"
"2","(3575,1150)","2","pure_quanta","I343";
;
PART_NUMBER"SP_CH4221MEE01"
VALUE"DIFF BUS_0.22UF"
$LOCATION"C827"
PIN_NAMES_ROTATE"TRUE"
CDS_LIB"pure_quanta"
CDS_LMAN_SYM_OUTLINE"-25,50,25,-50"
VOLTAGE"6.3V"
MATERIAL"X6S"
PACK_TYPE"C0201"
TOLERANCE"20%"
$LOCATION"C827"
CDS_LOCATION"C827"
$SEC"1"
CDS_SEC"1";
"2"
$PN"2"72;
"1"
$PN"1"28;
%"Q_CAP_DIFFBUS"
"2","(3575,1200)","2","pure_quanta","I344";
;
PART_NUMBER"SP_CH4221MEE01"
VALUE"DIFF BUS_0.22UF"
$LOCATION"C826"
PIN_NAMES_ROTATE"TRUE"
CDS_LIB"pure_quanta"
CDS_LMAN_SYM_OUTLINE"-25,50,25,-50"
VOLTAGE"6.3V"
MATERIAL"X6S"
PACK_TYPE"C0201"
TOLERANCE"20%"
$LOCATION"C826"
CDS_LOCATION"C826"
$SEC"1"
CDS_SEC"1";
"2"
$PN"2"70;
"1"
$PN"1"35;
%"Q_CAP_DIFFBUS"
"2","(3575,1600)","2","pure_quanta","I345";
;
PART_NUMBER"SP_CH4221MEE01"
VALUE"DIFF BUS_0.22UF"
$LOCATION"C822"
PIN_NAMES_ROTATE"TRUE"
CDS_LMAN_SYM_OUTLINE"-25,50,25,-50"
CDS_LIB"pure_quanta"
VOLTAGE"6.3V"
MATERIAL"X6S"
PACK_TYPE"C0201"
TOLERANCE"20%"
$LOCATION"C822"
CDS_LOCATION"C822"
$SEC"1"
CDS_SEC"1";
"2"
$PN"2"34;
"1"
$PN"1"44;
%"Q_CAP_DIFFBUS"
"2","(3575,1550)","2","pure_quanta","I346";
;
PART_NUMBER"SP_CH4221MEE01"
VALUE"DIFF BUS_0.22UF"
$LOCATION"C823"
PIN_NAMES_ROTATE"TRUE"
CDS_LIB"pure_quanta"
CDS_LMAN_SYM_OUTLINE"-25,50,25,-50"
VOLTAGE"6.3V"
MATERIAL"X6S"
PACK_TYPE"C0201"
TOLERANCE"20%"
$LOCATION"C823"
CDS_LOCATION"C823"
$SEC"1"
CDS_SEC"1";
"2"
$PN"2"33;
"1"
$PN"1"45;
%"TAP"
"1","(2600,2125)","2","standard","I347";
;
CDS_LIB"standard"
BODY_TYPE"PLUMBING"
HDL_TAP"TRUE";
"B \NAC \NWC"11;
"S \NAC"
BN"8"64;
%"TAP"
"1","(2600,2325)","2","standard","I348";
;
CDS_LIB"standard"
BODY_TYPE"PLUMBING"
HDL_TAP"TRUE";
"B \NAC \NWC"11;
"S \NAC"
BN"9"66;
%"TAP"
"1","(2600,2525)","2","standard","I349";
;
CDS_LIB"standard"
BODY_TYPE"PLUMBING"
HDL_TAP"TRUE";
"B \NAC \NWC"11;
"S \NAC"
BN"10"68;
%"TAP"
"1","(2850,2175)","2","standard","I350";
;
CDS_LIB"standard"
BODY_TYPE"PLUMBING"
HDL_TAP"TRUE";
"B \NAC \NWC"12;
"S \NAC"
BN"8"65;
%"TAP"
"1","(2850,2375)","2","standard","I351";
;
CDS_LIB"standard"
BODY_TYPE"PLUMBING"
HDL_TAP"TRUE";
"B \NAC \NWC"12;
"S \NAC"
BN"9"67;
%"TAP"
"1","(2600,2725)","2","standard","I352";
;
CDS_LIB"standard"
BODY_TYPE"PLUMBING"
HDL_TAP"TRUE";
"B \NAC \NWC"11;
"S \NAC"
BN"11"63;
%"TAP"
"1","(2600,2925)","2","standard","I353";
;
CDS_LIB"standard"
BODY_TYPE"PLUMBING"
HDL_TAP"TRUE";
"B \NAC \NWC"11;
"S \NAC"
BN"12"62;
%"TAP"
"1","(2850,2575)","2","standard","I354";
;
CDS_LIB"standard"
BODY_TYPE"PLUMBING"
HDL_TAP"TRUE";
"B \NAC \NWC"12;
"S \NAC"
BN"10"60;
%"TAP"
"1","(2850,2775)","2","standard","I355";
;
CDS_LIB"standard"
BODY_TYPE"PLUMBING"
HDL_TAP"TRUE";
"B \NAC \NWC"12;
"S \NAC"
BN"11"61;
%"TAP"
"1","(2850,2975)","2","standard","I356";
;
CDS_LIB"standard"
BODY_TYPE"PLUMBING"
HDL_TAP"TRUE";
"B \NAC \NWC"12;
"S \NAC"
BN"12"59;
%"TAP"
"1","(2600,3125)","2","standard","I357";
;
CDS_LIB"standard"
BODY_TYPE"PLUMBING"
HDL_TAP"TRUE";
"B \NAC \NWC"11;
"S \NAC"
BN"13"56;
%"TAP"
"1","(2600,3325)","2","standard","I358";
;
CDS_LIB"standard"
BODY_TYPE"PLUMBING"
HDL_TAP"TRUE";
"B \NAC \NWC"11;
"S \NAC"
BN"14"58;
%"TAP"
"1","(2600,3525)","2","standard","I359";
;
CDS_LIB"standard"
BODY_TYPE"PLUMBING"
HDL_TAP"TRUE";
"B \NAC \NWC"11;
"S \NAC"
BN"15"57;
%"TAP"
"1","(2850,3175)","2","standard","I360";
;
CDS_LIB"standard"
BODY_TYPE"PLUMBING"
HDL_TAP"TRUE";
"B \NAC \NWC"12;
"S \NAC"
BN"13"55;
%"TAP"
"1","(2850,3375)","2","standard","I361";
;
CDS_LIB"standard"
BODY_TYPE"PLUMBING"
HDL_TAP"TRUE";
"B \NAC \NWC"12;
"S \NAC"
BN"14"54;
%"TAP"
"1","(2850,3575)","2","standard","I362";
;
CDS_LIB"standard"
BODY_TYPE"PLUMBING"
HDL_TAP"TRUE";
"B \NAC \NWC"12;
"S \NAC"
BN"15"53;
%"Q_CAP_DIFFBUS"
"2","(3575,2175)","2","pure_quanta","I363";
;
PART_NUMBER"SP_CH4221MEE01"
VALUE"DIFF BUS_0.22UF"
$LOCATION"C820"
CDS_LMAN_SYM_OUTLINE"-25,50,25,-50"
CDS_LIB"pure_quanta"
PIN_NAMES_ROTATE"TRUE"
VOLTAGE"6.3V"
MATERIAL"X6S"
PACK_TYPE"C0201"
TOLERANCE"20%"
$LOCATION"C820"
CDS_LOCATION"C820"
$SEC"1"
CDS_SEC"1";
"2"
$PN"2"65;
"1"
$PN"1"43;
%"Q_CAP_DIFFBUS"
"2","(3575,2125)","2","pure_quanta","I364";
;
PART_NUMBER"SP_CH4221MEE01"
VALUE"DIFF BUS_0.22UF"
$LOCATION"C821"
CDS_LMAN_SYM_OUTLINE"-25,50,25,-50"
CDS_LIB"pure_quanta"
PIN_NAMES_ROTATE"TRUE"
VOLTAGE"6.3V"
MATERIAL"X6S"
PACK_TYPE"C0201"
TOLERANCE"20%"
$LOCATION"C821"
CDS_LOCATION"C821"
$SEC"1"
CDS_SEC"1";
"2"
$PN"2"64;
"1"
$PN"1"27;
%"Q_CAP_DIFFBUS"
"2","(3575,2375)","2","pure_quanta","I365";
;
PART_NUMBER"SP_CH4221MEE01"
VALUE"DIFF BUS_0.22UF"
$LOCATION"C818"
CDS_LIB"pure_quanta"
CDS_LMAN_SYM_OUTLINE"-25,50,25,-50"
PIN_NAMES_ROTATE"TRUE"
VOLTAGE"6.3V"
MATERIAL"X6S"
PACK_TYPE"C0201"
TOLERANCE"20%"
$LOCATION"C818"
CDS_LOCATION"C818"
$SEC"1"
CDS_SEC"1";
"2"
$PN"2"67;
"1"
$PN"1"42;
%"Q_CAP_DIFFBUS"
"2","(3575,2325)","2","pure_quanta","I366";
;
PART_NUMBER"SP_CH4221MEE01"
VALUE"DIFF BUS_0.22UF"
$LOCATION"C819"
CDS_LMAN_SYM_OUTLINE"-25,50,25,-50"
CDS_LIB"pure_quanta"
PIN_NAMES_ROTATE"TRUE"
VOLTAGE"6.3V"
MATERIAL"X6S"
PACK_TYPE"C0201"
TOLERANCE"20%"
$LOCATION"C819"
CDS_LOCATION"C819"
$SEC"1"
CDS_SEC"1";
"2"
$PN"2"66;
"1"
$PN"1"26;
%"Q_CAP_DIFFBUS"
"2","(3575,2525)","2","pure_quanta","I367";
;
PART_NUMBER"SP_CH4221MEE01"
VALUE"DIFF BUS_0.22UF"
$LOCATION"C817"
CDS_LMAN_SYM_OUTLINE"-25,50,25,-50"
CDS_LIB"pure_quanta"
PIN_NAMES_ROTATE"TRUE"
VOLTAGE"6.3V"
MATERIAL"X6S"
PACK_TYPE"C0201"
TOLERANCE"20%"
$LOCATION"C817"
CDS_LOCATION"C817"
$SEC"1"
CDS_SEC"1";
"2"
$PN"2"68;
"1"
$PN"1"25;
%"Q_CAP_DIFFBUS"
"2","(3575,2575)","2","pure_quanta","I368";
;
PART_NUMBER"SP_CH4221MEE01"
VALUE"DIFF BUS_0.22UF"
$LOCATION"C816"
CDS_LMAN_SYM_OUTLINE"-25,50,25,-50"
CDS_LIB"pure_quanta"
PIN_NAMES_ROTATE"TRUE"
VOLTAGE"6.3V"
MATERIAL"X6S"
PACK_TYPE"C0201"
TOLERANCE"20%"
$LOCATION"C816"
CDS_LOCATION"C816"
$SEC"1"
CDS_SEC"1";
"2"
$PN"2"60;
"1"
$PN"1"41;
%"Q_CAP_DIFFBUS"
"2","(3575,2725)","2","pure_quanta","I369";
;
PART_NUMBER"SP_CH4221MEE01"
VALUE"DIFF BUS_0.22UF"
$LOCATION"C815"
CDS_LIB"pure_quanta"
CDS_LMAN_SYM_OUTLINE"-25,50,25,-50"
PIN_NAMES_ROTATE"TRUE"
VOLTAGE"6.3V"
MATERIAL"X6S"
PACK_TYPE"C0201"
TOLERANCE"20%"
$LOCATION"C815"
CDS_LOCATION"C815"
$SEC"1"
CDS_SEC"1";
"2"
$PN"2"63;
"1"
$PN"1"24;
%"Q_CAP_DIFFBUS"
"2","(3575,2775)","2","pure_quanta","I370";
;
PART_NUMBER"SP_CH4221MEE01"
VALUE"DIFF BUS_0.22UF"
$LOCATION"C814"
CDS_LIB"pure_quanta"
CDS_LMAN_SYM_OUTLINE"-25,50,25,-50"
PIN_NAMES_ROTATE"TRUE"
VOLTAGE"6.3V"
MATERIAL"X6S"
PACK_TYPE"C0201"
TOLERANCE"20%"
$LOCATION"C814"
CDS_LOCATION"C814"
$SEC"1"
CDS_SEC"1";
"2"
$PN"2"61;
"1"
$PN"1"23;
%"Q_CAP_DIFFBUS"
"2","(3575,2975)","2","pure_quanta","I371";
;
PART_NUMBER"SP_CH4221MEE01"
VALUE"DIFF BUS_0.22UF"
$LOCATION"C812"
CDS_LMAN_SYM_OUTLINE"-25,50,25,-50"
CDS_LIB"pure_quanta"
PIN_NAMES_ROTATE"TRUE"
VOLTAGE"6.3V"
MATERIAL"X6S"
PACK_TYPE"C0201"
TOLERANCE"20%"
$LOCATION"C812"
CDS_LOCATION"C812"
$SEC"1"
CDS_SEC"1";
"2"
$PN"2"59;
"1"
$PN"1"22;
%"Q_CAP_DIFFBUS"
"2","(3575,2925)","2","pure_quanta","I372";
;
PART_NUMBER"SP_CH4221MEE01"
VALUE"DIFF BUS_0.22UF"
$LOCATION"C813"
CDS_LMAN_SYM_OUTLINE"-25,50,25,-50"
CDS_LIB"pure_quanta"
PIN_NAMES_ROTATE"TRUE"
VOLTAGE"6.3V"
MATERIAL"X6S"
PACK_TYPE"C0201"
TOLERANCE"20%"
$LOCATION"C813"
CDS_LOCATION"C813"
$SEC"1"
CDS_SEC"1";
"2"
$PN"2"62;
"1"
$PN"1"40;
%"Q_CAP_DIFFBUS"
"2","(3575,3125)","2","pure_quanta","I373";
;
PART_NUMBER"SP_CH4221MEE01"
VALUE"DIFF BUS_0.22UF"
$LOCATION"C811"
CDS_LMAN_SYM_OUTLINE"-25,50,25,-50"
CDS_LIB"pure_quanta"
PIN_NAMES_ROTATE"TRUE"
VOLTAGE"6.3V"
MATERIAL"X6S"
PACK_TYPE"C0201"
TOLERANCE"20%"
$LOCATION"C811"
CDS_LOCATION"C811"
$SEC"1"
CDS_SEC"1";
"2"
$PN"2"56;
"1"
$PN"1"21;
%"Q_CAP_DIFFBUS"
"2","(3575,3175)","2","pure_quanta","I374";
;
PART_NUMBER"SP_CH4221MEE01"
VALUE"DIFF BUS_0.22UF"
$LOCATION"C810"
CDS_LMAN_SYM_OUTLINE"-25,50,25,-50"
CDS_LIB"pure_quanta"
PIN_NAMES_ROTATE"TRUE"
VOLTAGE"6.3V"
MATERIAL"X6S"
PACK_TYPE"C0201"
TOLERANCE"20%"
$LOCATION"C810"
CDS_LOCATION"C810"
$SEC"1"
CDS_SEC"1";
"2"
$PN"2"55;
"1"
$PN"1"39;
%"Q_CAP_DIFFBUS"
"2","(3575,3325)","2","pure_quanta","I375";
;
PART_NUMBER"SP_CH4221MEE01"
VALUE"DIFF BUS_0.22UF"
$LOCATION"C809"
CDS_LMAN_SYM_OUTLINE"-25,50,25,-50"
CDS_LIB"pure_quanta"
PIN_NAMES_ROTATE"TRUE"
VOLTAGE"6.3V"
MATERIAL"X6S"
PACK_TYPE"C0201"
TOLERANCE"20%"
$LOCATION"C809"
CDS_LOCATION"C809"
$SEC"1"
CDS_SEC"1";
"2"
$PN"2"58;
"1"
$PN"1"20;
%"Q_CAP_DIFFBUS"
"2","(3575,3375)","2","pure_quanta","I376";
;
PART_NUMBER"SP_CH4221MEE01"
VALUE"DIFF BUS_0.22UF"
$LOCATION"C808"
CDS_LMAN_SYM_OUTLINE"-25,50,25,-50"
CDS_LIB"pure_quanta"
PIN_NAMES_ROTATE"TRUE"
VOLTAGE"6.3V"
MATERIAL"X6S"
PACK_TYPE"C0201"
TOLERANCE"20%"
$LOCATION"C808"
CDS_LOCATION"C808"
$SEC"1"
CDS_SEC"1";
"2"
$PN"2"54;
"1"
$PN"1"38;
%"Q_CAP_DIFFBUS"
"2","(3575,3575)","2","pure_quanta","I377";
;
PART_NUMBER"SP_CH4221MEE01"
VALUE"DIFF BUS_0.22UF"
MATERIAL"X6S"
PACK_TYPE"C0201"
VOLTAGE"6.3V"
TOLERANCE"20%"
$LOCATION"C806"
CDS_LIB"pure_quanta"
CDS_LMAN_SYM_OUTLINE"-25,50,25,-50"
PIN_NAMES_ROTATE"TRUE"
$LOCATION"C806"
CDS_LOCATION"C806"
$SEC"1"
CDS_SEC"1";
"2"
$PN"2"53;
"1"
$PN"1"37;
%"Q_CAP_DIFFBUS"
"2","(3575,3525)","2","pure_quanta","I378";
;
PART_NUMBER"SP_CH4221MEE01"
VALUE"DIFF BUS_0.22UF"
$LOCATION"C807"
CDS_LMAN_SYM_OUTLINE"-25,50,25,-50"
CDS_LIB"pure_quanta"
PIN_NAMES_ROTATE"TRUE"
VOLTAGE"6.3V"
MATERIAL"X6S"
PACK_TYPE"C0201"
TOLERANCE"20%"
$LOCATION"C807"
CDS_LOCATION"C807"
$SEC"1"
CDS_SEC"1";
"2"
$PN"2"57;
"1"
$PN"1"19;
%"TAP"
"1","(4125,200)","0","standard","I379";
;
CDS_LIB"standard"
BODY_TYPE"PLUMBING"
HDL_TAP"TRUE";
"B \NAC \NWC"13;
"S \NAC"
BN"0"52;
%"TAP"
"1","(4325,150)","0","standard","I380";
;
CDS_LIB"standard"
BODY_TYPE"PLUMBING"
HDL_TAP"TRUE";
"B \NAC \NWC"14;
"S \NAC"
BN"0"29;
%"TAP"
"1","(4125,400)","0","standard","I381";
;
CDS_LIB"standard"
BODY_TYPE"PLUMBING"
HDL_TAP"TRUE";
"B \NAC \NWC"13;
"S \NAC"
BN"1"51;
%"TAP"
"1","(4325,350)","0","standard","I382";
;
CDS_LIB"standard"
BODY_TYPE"PLUMBING"
HDL_TAP"TRUE";
"B \NAC \NWC"14;
"S \NAC"
BN"1"30;
%"TAP"
"1","(4125,600)","0","standard","I383";
;
CDS_LIB"standard"
BODY_TYPE"PLUMBING"
HDL_TAP"TRUE";
"B \NAC \NWC"13;
"S \NAC"
BN"2"50;
%"TAP"
"1","(4325,550)","0","standard","I384";
;
CDS_LIB"standard"
BODY_TYPE"PLUMBING"
HDL_TAP"TRUE";
"B \NAC \NWC"14;
"S \NAC"
BN"2"31;
%"TAP"
"1","(4325,750)","0","standard","I385";
;
CDS_LIB"standard"
BODY_TYPE"PLUMBING"
HDL_TAP"TRUE";
"B \NAC \NWC"14;
"S \NAC"
BN"3"32;
%"TAP"
"1","(4125,800)","0","standard","I386";
;
CDS_LIB"standard"
BODY_TYPE"PLUMBING"
HDL_TAP"TRUE";
"B \NAC \NWC"13;
"S \NAC"
BN"3"49;
%"TAP"
"1","(4325,950)","0","standard","I387";
;
CDS_LIB"standard"
BODY_TYPE"PLUMBING"
HDL_TAP"TRUE";
"B \NAC \NWC"14;
"S \NAC"
BN"4"36;
%"TAP"
"1","(4125,1200)","0","standard","I388";
;
CDS_LIB"standard"
BODY_TYPE"PLUMBING"
HDL_TAP"TRUE";
"B \NAC \NWC"13;
"S \NAC"
BN"5"35;
%"TAP"
"1","(4325,1150)","0","standard","I389";
;
CDS_LIB"standard"
BODY_TYPE"PLUMBING"
HDL_TAP"TRUE";
"B \NAC \NWC"14;
"S \NAC"
BN"5"28;
%"TAP"
"1","(4125,1400)","0","standard","I390";
;
CDS_LIB"standard"
BODY_TYPE"PLUMBING"
HDL_TAP"TRUE";
"B \NAC \NWC"13;
"S \NAC"
BN"6"47;
%"TAP"
"1","(4325,1350)","0","standard","I391";
;
CDS_LIB"standard"
BODY_TYPE"PLUMBING"
HDL_TAP"TRUE";
"B \NAC \NWC"14;
"S \NAC"
BN"6"46;
%"TAP"
"1","(4125,1600)","0","standard","I392";
;
CDS_LIB"standard"
BODY_TYPE"PLUMBING"
HDL_TAP"TRUE";
"B \NAC \NWC"13;
"S \NAC"
BN"7"44;
%"TAP"
"1","(4325,1550)","0","standard","I393";
;
CDS_LIB"standard"
BODY_TYPE"PLUMBING"
HDL_TAP"TRUE";
"B \NAC \NWC"14;
"S \NAC"
BN"7"45;
%"TAP"
"1","(4125,2175)","0","standard","I396";
;
CDS_LIB"standard"
BODY_TYPE"PLUMBING"
HDL_TAP"TRUE";
"B \NAC \NWC"15;
"S \NAC"
BN"8"43;
%"TAP"
"1","(4325,2125)","0","standard","I397";
;
CDS_LIB"standard"
BODY_TYPE"PLUMBING"
HDL_TAP"TRUE";
"B \NAC \NWC"16;
"S \NAC"
BN"8"27;
%"TAP"
"1","(4125,2375)","0","standard","I398";
;
CDS_LIB"standard"
BODY_TYPE"PLUMBING"
HDL_TAP"TRUE";
"B \NAC \NWC"15;
"S \NAC"
BN"9"42;
%"TAP"
"1","(4325,2525)","0","standard","I399";
;
CDS_LIB"standard"
BODY_TYPE"PLUMBING"
HDL_TAP"TRUE";
"B \NAC \NWC"16;
"S \NAC"
BN"10"25;
%"TAP"
"1","(4325,2325)","0","standard","I400";
;
CDS_LIB"standard"
BODY_TYPE"PLUMBING"
HDL_TAP"TRUE";
"B \NAC \NWC"16;
"S \NAC"
BN"9"26;
%"TAP"
"1","(4125,2575)","0","standard","I401";
;
CDS_LIB"standard"
BODY_TYPE"PLUMBING"
HDL_TAP"TRUE";
"B \NAC \NWC"15;
"S \NAC"
BN"10"41;
%"TAP"
"1","(4125,2775)","0","standard","I402";
;
CDS_LIB"standard"
BODY_TYPE"PLUMBING"
HDL_TAP"TRUE";
"B \NAC \NWC"15;
"S \NAC"
BN"11"23;
%"TAP"
"1","(4325,2725)","0","standard","I403";
;
CDS_LIB"standard"
BODY_TYPE"PLUMBING"
HDL_TAP"TRUE";
"B \NAC \NWC"16;
"S \NAC"
BN"11"24;
%"TAP"
"1","(4125,2975)","0","standard","I404";
;
CDS_LIB"standard"
BODY_TYPE"PLUMBING"
HDL_TAP"TRUE";
"B \NAC \NWC"15;
"S \NAC"
BN"12"22;
%"TAP"
"1","(4325,2925)","0","standard","I405";
;
CDS_LIB"standard"
BODY_TYPE"PLUMBING"
HDL_TAP"TRUE";
"B \NAC \NWC"16;
"S \NAC"
BN"12"40;
%"TAP"
"1","(4125,3175)","0","standard","I406";
;
CDS_LIB"standard"
BODY_TYPE"PLUMBING"
HDL_TAP"TRUE";
"B \NAC \NWC"15;
"S \NAC"
BN"13"39;
%"TAP"
"1","(4325,3125)","0","standard","I407";
;
CDS_LIB"standard"
BODY_TYPE"PLUMBING"
HDL_TAP"TRUE";
"B \NAC \NWC"16;
"S \NAC"
BN"13"21;
%"TAP"
"1","(4325,3325)","0","standard","I408";
;
CDS_LIB"standard"
BODY_TYPE"PLUMBING"
HDL_TAP"TRUE";
"B \NAC \NWC"16;
"S \NAC"
BN"14"20;
%"TAP"
"1","(4125,3575)","0","standard","I409";
;
CDS_LIB"standard"
BODY_TYPE"PLUMBING"
HDL_TAP"TRUE";
"B \NAC \NWC"15;
"S \NAC"
BN"15"37;
%"TAP"
"1","(4125,3375)","0","standard","I410";
;
CDS_LIB"standard"
BODY_TYPE"PLUMBING"
HDL_TAP"TRUE";
"B \NAC \NWC"15;
"S \NAC"
BN"14"38;
%"TAP"
"1","(4325,3525)","0","standard","I411";
;
CDS_LIB"standard"
BODY_TYPE"PLUMBING"
HDL_TAP"TRUE";
"B \NAC \NWC"16;
"S \NAC"
BN"15"19;
%"TAP"
"1","(4125,1000)","0","standard","I414";
;
CDS_LIB"standard"
BODY_TYPE"PLUMBING"
HDL_TAP"TRUE";
"B \NAC \NWC"13;
"S \NAC"
BN"4"48;
%"Q_CAP_DIFFBUS"
"2","(3575,1350)","2","pure_quanta","I415";
;
PART_NUMBER"SP_CH4221MEE01"
VALUE"DIFF BUS_0.22UF"
$LOCATION"C825"
PIN_NAMES_ROTATE"TRUE"
CDS_LIB"pure_quanta"
CDS_LMAN_SYM_OUTLINE"-25,50,25,-50"
VOLTAGE"6.3V"
MATERIAL"X6S"
PACK_TYPE"C0201"
TOLERANCE"20%"
$LOCATION"C825"
CDS_LOCATION"C825"
$SEC"1"
CDS_SEC"1";
"2"
$PN"2"71;
"1"
$PN"1"46;
%"Q_CAP_DIFFBUS"
"2","(3575,1400)","2","pure_quanta","I416";
;
PART_NUMBER"SP_CH4221MEE01"
VALUE"DIFF BUS_0.22UF"
$LOCATION"C824"
PIN_NAMES_ROTATE"TRUE"
CDS_LIB"pure_quanta"
CDS_LMAN_SYM_OUTLINE"-25,50,25,-50"
VOLTAGE"6.3V"
MATERIAL"X6S"
PACK_TYPE"C0201"
TOLERANCE"20%"
$LOCATION"C824"
CDS_LOCATION"C824"
$SEC"1"
CDS_SEC"1";
"2"
$PN"2"69;
"1"
$PN"1"47;
END.
